# SCM (Grand Teton) — schematic netlist excerpt (pin names and nets, part order shuffled) for the footprints in the layout excerpt that follows; sources: Cadence DE-HDL packaged netlist, KiCad conversion of 12092022_DA0F0TMDCD0_F0T_Management_Board_D_brd_V3_OCP.brd

R346  Q_RES  120 1% CHIP  pkg 0402LF  page 20 : A = GND ; B = M_BMC_DDR4_MBA0
C89  Q_CAP  0.1UF 25V 10% X7R  pkg 0402  page 16 : A = P1V8_AUX ; B = GND

(kicad_pcb
	(version 20260206)
	(generator "pcbnew")
	(generator_version "10.0")
	(general
		(thickness 1.6)
		(legacy_teardrops no)
	)
	(paper "A4")
	(title_block
		(title "12092022_DA0F0TMDCD0_F0T_Management_Board_D_brd_V3_OCP.brd")
		(comment 1 "Grand Teton / footprints 1257-1258 of 1440")
	)
	(layers
		(0 "F.Cu" signal "TOP")
		(4 "In1.Cu" signal "GND")
		(6 "In2.Cu" signal "IN1")
		(8 "In3.Cu" signal "GND1")
		(10 "In4.Cu" signal "IN2")
		(12 "In5.Cu" signal "VCC")
		(14 "In6.Cu" signal "VCC1")
		(16 "In7.Cu" signal "IN3")
		(18 "In8.Cu" signal "GND2")
		(20 "In9.Cu" signal "IN4")
		(22 "In10.Cu" signal "GND3")
		(2 "B.Cu" signal "BOTTOM")
		(9 "F.Adhes" user "F.Adhesive")
		(11 "B.Adhes" user "B.Adhesive")
		(13 "F.Paste" user "Package Geometry/Pastemask Top")
		(15 "B.Paste" user "Package Geometry/Pastemask Bottom")
		(5 "F.SilkS" user "Ref Des/Silkscreen Top")
		(7 "B.SilkS" user "Ref Des/Silkscreen Bottom")
		(1 "F.Mask" user "Board Geometry/Soldermask Top")
		(3 "B.Mask" user "Board Geometry/Soldermask Bottom")
		(17 "Dwgs.User" user "User.Drawings")
		(19 "Cmts.User" user "User.Comments")
		(21 "Eco1.User" user "User.Eco1")
		(23 "Eco2.User" user "User.Eco2")
		(25 "Edge.Cuts" user "Board Geometry/Outline")
		(27 "Margin" user)
		(31 "F.CrtYd" user "Package Geometry/Place Bound Top")
		(29 "B.CrtYd" user "Package Geometry/Place Bound Bottom")
		(35 "F.Fab" user "Ref Des/Assembly Top")
		(33 "B.Fab" user "Ref Des/Assembly Bottom")
	)
	(footprint ""
		(layer "B.Cu")
		(at 79.739744 -35.540188 -90)
		(property "Reference" "R346"
			(at 0 0 90)
			(layer "B.SilkS")
			(hide yes)
			(effects
				(font
					(size 1.27 1.27)
				)
				(justify mirror)
			)
		)
		(property "Value" ""
			(at 0 0 90)
			(layer "B.Fab")
			(effects
				(font
					(size 1.27 1.27)
				)
				(justify mirror)
			)
		)
		(duplicate_pad_numbers_are_jumpers no)
		(fp_line
			(start -0.7874 0.4064)
			(end 0.7874 0.4064)
			(stroke
				(width 0.1524)
				(type default)
			)
			(layer "B.SilkS")
		)
		(fp_line
			(start 0.7874 0.4064)
			(end 0.7874 -0.4064)
			(stroke
				(width 0.1524)
				(type default)
			)
			(layer "B.SilkS")
		)
		(fp_line
			(start -0.7874 -0.4064)
			(end -0.7874 0.4064)
			(stroke
				(width 0.1524)
				(type default)
			)
			(layer "B.SilkS")
		)
		(fp_line
			(start 0.7874 -0.4064)
			(end -0.7874 -0.4064)
			(stroke
				(width 0.1524)
				(type default)
			)
			(layer "B.SilkS")
		)
		(fp_line
			(start -0.67945 0.3048)
			(end -0.120396 0.3048)
			(stroke
				(width 0.1)
				(type default)
			)
			(layer "B.Fab")
		)
		(fp_line
			(start -0.120396 0.3048)
			(end -0.120396 0.2794)
			(stroke
				(width 0.1)
				(type default)
			)
			(layer "B.Fab")
		)
		(fp_line
			(start 0.12065 0.3048)
			(end 0.67945 0.3048)
			(stroke
				(width 0.1)
				(type default)
			)
			(layer "B.Fab")
		)
		(fp_line
			(start 0.67945 0.3048)
			(end 0.67945 -0.305054)
			(stroke
				(width 0.1)
				(type default)
			)
			(layer "B.Fab")
		)
		(fp_line
			(start -0.120396 0.2794)
			(end 0.12065 0.2794)
			(stroke
				(width 0.1)
				(type default)
			)
			(layer "B.Fab")
		)
		(fp_line
			(start 0.12065 0.2794)
			(end 0.12065 0.3048)
			(stroke
				(width 0.1)
				(type default)
			)
			(layer "B.Fab")
		)
		(fp_line
			(start -0.12065 -0.2794)
			(end -0.12065 -0.3048)
			(stroke
				(width 0.1)
				(type default)
			)
			(layer "B.Fab")
		)
		(fp_line
			(start 0.12065 -0.2794)
			(end -0.12065 -0.2794)
			(stroke
				(width 0.1)
				(type default)
			)
			(layer "B.Fab")
		)
		(fp_line
			(start -0.67945 -0.3048)
			(end -0.67945 0.3048)
			(stroke
				(width 0.1)
				(type default)
			)
			(layer "B.Fab")
		)
		(fp_line
			(start -0.12065 -0.3048)
			(end -0.67945 -0.3048)
			(stroke
				(width 0.1)
				(type default)
			)
			(layer "B.Fab")
		)
		(fp_line
			(start 0.12065 -0.305054)
			(end 0.12065 -0.2794)
			(stroke
				(width 0.1)
				(type default)
			)
			(layer "B.Fab")
		)
		(fp_line
			(start 0.67945 -0.305054)
			(end 0.12065 -0.305054)
			(stroke
				(width 0.1)
				(type default)
			)
			(layer "B.Fab")
		)
		(pad "1" smd circle
			(at 0.40005 0 90)
			(size 0 0)
			(layers "B.Cu" "B.Mask" "B.Paste")
			(net "GND")
		)
		(pad "2" smd circle
			(at -0.40005 0 90)
			(size 0 0)
			(layers "B.Cu" "B.Mask" "B.Paste")
			(net "M_BMC_DDR4_MBA0")
		)
	)
	(footprint ""
		(layer "B.Cu")
		(at 54.93131 -46.073314 90)
		(property "Reference" "C89"
			(at 0 0 90)
			(layer "B.SilkS")
			(hide yes)
			(effects
				(font
					(size 1.27 1.27)
				)
				(justify mirror)
			)
		)
		(property "Value" ""
			(at 0 0 90)
			(layer "B.Fab")
			(effects
				(font
					(size 1.27 1.27)
				)
				(justify mirror)
			)
		)
		(duplicate_pad_numbers_are_jumpers no)
		(fp_line
			(start 0.7874 -0.4064)
			(end -0.7874 -0.4064)
			(stroke
				(width 0.1524)
				(type default)
			)
			(layer "B.SilkS")
		)
		(fp_line
			(start -0.7874 -0.4064)
			(end -0.7874 0.4064)
			(stroke
				(width 0.1524)
				(type default)
			)
			(layer "B.SilkS")
		)
		(fp_line
			(start 0.7874 0.4064)
			(end 0.7874 -0.4064)
			(stroke
				(width 0.1524)
				(type default)
			)
			(layer "B.SilkS")
		)
		(fp_line
			(start -0.7874 0.4064)
			(end 0.7874 0.4064)
			(stroke
				(width 0.1524)
				(type default)
			)
			(layer "B.SilkS")
		)
		(fp_line
			(start 0.67945 -0.305054)
			(end 0.12065 -0.305054)
			(stroke
				(width 0.1)
				(type default)
			)
			(layer "B.Fab")
		)
		(fp_line
			(start 0.12065 -0.305054)
			(end 0.12065 -0.2794)
			(stroke
				(width 0.1)
				(type default)
			)
			(layer "B.Fab")
		)
		(fp_line
			(start -0.12065 -0.3048)
			(end -0.67945 -0.3048)
			(stroke
				(width 0.1)
				(type default)
			)
			(layer "B.Fab")
		)
		(fp_line
			(start -0.67945 -0.3048)
			(end -0.67945 0.3048)
			(stroke
				(width 0.1)
				(type default)
			)
			(layer "B.Fab")
		)
		(fp_line
			(start 0.12065 -0.2794)
			(end -0.12065 -0.2794)
			(stroke
				(width 0.1)
				(type default)
			)
			(layer "B.Fab")
		)
		(fp_line
			(start -0.12065 -0.2794)
			(end -0.12065 -0.3048)
			(stroke
				(width 0.1)
				(type default)
			)
			(layer "B.Fab")
		)
		(fp_line
			(start 0.12065 0.2794)
			(end 0.12065 0.3048)
			(stroke
				(width 0.1)
				(type default)
			)
			(layer "B.Fab")
		)
		(fp_line
			(start -0.120396 0.2794)
			(end 0.12065 0.2794)
			(stroke
				(width 0.1)
				(type default)
			)
			(layer "B.Fab")
		)
		(fp_line
			(start 0.67945 0.3048)
			(end 0.67945 -0.305054)
			(stroke
				(width 0.1)
				(type default)
			)
			(layer "B.Fab")
		)
		(fp_line
			(start 0.12065 0.3048)
			(end 0.67945 0.3048)
			(stroke
				(width 0.1)
				(type default)
			)
			(layer "B.Fab")
		)
		(fp_line
			(start -0.120396 0.3048)
			(end -0.120396 0.2794)
			(stroke
				(width 0.1)
				(type default)
			)
			(layer "B.Fab")
		)
		(fp_line
			(start -0.67945 0.3048)
			(end -0.120396 0.3048)
			(stroke
				(width 0.1)
				(type default)
			)
			(layer "B.Fab")
		)
		(pad "1" smd circle
			(at 0.40005 0 270)
			(size 0 0)
			(layers "B.Cu" "B.Mask" "B.Paste")
			(net "P1V8_AUX")
		)
		(pad "2" smd circle
			(at -0.40005 0 270)
			(size 0 0)
			(layers "B.Cu" "B.Mask" "B.Paste")
			(net "GND")
		)
	)
)
